;LEADER: 12 
;HEADER: 
;CODE  : ASCII 
;FILE  : 9324_DA0F0TMBIJ0_F0T_Motherboard_J_v01_20230324_0910-bd-18-8.drl for backdrilling ... from layer BOTTOM to layer GND3
;DESIGN: 9324_DA0F0TMBIJ0_F0T_Motherboard_J_v01_20230324_0910.brd
;MUST-NOT-CUT-LAYER = IN3,  MAX_DRILL_DEPTH = 61.30 MILS,  MFG_STUB_LENGTH = 0.00 MILS
;   BackdrillSize 1. = 15.700000 Tolerance = +0.000000/-0.000000 NON_PLATED MILS Quantity = 1200
;   BackdrillSize 2. = 17.700000 Tolerance = +0.000000/-0.000000 NON_PLATED MILS Quantity = 228
%
G90
X0066099Y1231955
X0066099Y1228609
X0066099Y1215223
X0066099Y1221916
X0066099Y1238648
X0066099Y1245341
X0066099Y0957546
X0036399Y0957546
X0066099Y0967585
X0052541Y0964239
X0036399Y0967585
X0066099Y0960892
X0036399Y0960892
X0066099Y0827034
X0066099Y0823688
X0066099Y0810302
X0066099Y0816995
X0066099Y0833727
X0066099Y0840420
X0141641Y0783530
X0141641Y0770144
X0141641Y0776837
X0125499Y0773491
X0125499Y0780184
X0082241Y0820341
X0082241Y0823688
X0082241Y0806955
X0082241Y0813648
X0082241Y0830381
X0082241Y0837074
X0141641Y0857152
X0125499Y0790223
X0125499Y0863845
X0141641Y0786877
X0141641Y0860499
X0125499Y0786877
X0125499Y0860499
X0125499Y0870538
X0125499Y0877231
X0141641Y0880577
X0141641Y0793570
X0141641Y0800263
X0125499Y0796916
X0125499Y0803609
X0141641Y0843766
X0141641Y0850459
X0125499Y0847113
X0125499Y0853806
X0141641Y0867192
X0141641Y0873885
X0082241Y0964239
X0125499Y0957546
X0095799Y0957546
X0141641Y0893963
X0125499Y0900656
X0141641Y0897310
X0125499Y0897310
X0141641Y0887270
X0125499Y0883924
X0125499Y0890617
X0141641Y0904003
X0141641Y0910696
X0125499Y0907349
X0125499Y0914042
X0125499Y0960892
X0095799Y0960892
X0155199Y0957546
X0155199Y0960892
X0141641Y1078018
X0141641Y1081365
X0125499Y1081365
X0141641Y1064633
X0141641Y1071326
X0125499Y1067979
X0125499Y1074672
X0141641Y1114829
X0125499Y1084711
X0125499Y1121522
X0141641Y1118176
X0125499Y1118176
X0141641Y1101444
X0141641Y1108137
X0125499Y1104790
X0125499Y1111483
X0141641Y1124869
X0141641Y1131562
X0125499Y1128215
X0125499Y1134908
X0141641Y1175066
X0141641Y1181759
X0125499Y1178412
X0141641Y1088058
X0141641Y1094751
X0125499Y1091404
X0125499Y1098097
X0082241Y1225263
X0082241Y1228609
X0082241Y1211877
X0082241Y1218570
X0082241Y1235302
X0082241Y1241995
X0141641Y1188452
X0125499Y1195144
X0141641Y1191798
X0125499Y1191798
X0125499Y1201837
X0125499Y1208530
X0125499Y1185105
X0141641Y1198491
X0141641Y1205184
X0184899Y0957546
X0184899Y0960892
X0244299Y0957546
X0214599Y0957546
X0244299Y0960892
X0214599Y0960892
X0367378Y0848176
X0365527Y0844971
X0359978Y0848176
X0358127Y0844971
X0352578Y0848176
X0348878Y0848176
X0371079Y0841467
X0369227Y0844971
X0363679Y0841467
X0361827Y0844971
X0356279Y0841467
X0354427Y0844971
X0350727Y0851380
X0371078Y0893036
X0351162Y1108630
X0353012Y1111834
X0354861Y1102221
X0347461Y1115039
X0341912Y1111834
X0345611Y1105426
X0353011Y1105426
X0349312Y1111834
X0351161Y1102221
X0345611Y1111834
X0343762Y1108630
X0341911Y1105426
X0380762Y1115039
X0382611Y1105426
X0375211Y1111834
X0378912Y1105426
X0412211Y1086200
X0427012Y1086200
X0428861Y1089404
X0423311Y1086200
X0430711Y1092608
X0425162Y1095813
X0419611Y1092608
X0402961Y1089404
X0414062Y1089404
X0408511Y1092608
X0386311Y1111834
X0384462Y1108630
X0378911Y1111834
X0380762Y1102221
X0377062Y1108630
X0375211Y1105426
X0430710Y1086200
X0419611Y1086200
X0427011Y1092608
X0423311Y1092608
X0421462Y1089404
X0404811Y1086200
X0410362Y1089404
X0406662Y1089404
X0382611Y1111834
X0386311Y1105426
X0382611Y1086200
X0380762Y1089404
X0375211Y1086200
X0377062Y1089404
X0406662Y1082995
X0410362Y1082995
X0414062Y1082995
X0425162Y1082995
X0402962Y1082995
X0408511Y1079791
X0382611Y1009297
X0380762Y1012501
X0375211Y1009297
X0377062Y1012501
X0380762Y1082995
X0377062Y1082995
X0384462Y1082995
X0373362Y1082995
X0380762Y1076587
X0382611Y1079791
X0377062Y1076587
X0375211Y1079791
X0380762Y0999684
X0382611Y1002888
X0377062Y0999684
X0375211Y1002888
X0380760Y1025318
X0384462Y1044544
X0380762Y1063770
X0373360Y1025318
X0377062Y1044544
X0377062Y1063770
X0384462Y1025318
X0380762Y1044544
X0384462Y1063770
X0377062Y1025318
X0373362Y1044544
X0373362Y1063770
X0375211Y1066974
X0377062Y1070178
X0380762Y1038136
X0382611Y1041340
X0377062Y1038136
X0375211Y1041340
X0382611Y1047749
X0380762Y1050952
X0375211Y1047749
X0377062Y1050952
X0380762Y1057361
X0382611Y1060565
X0377062Y1057361
X0375211Y1060565
X0382611Y1066974
X0380762Y1070178
X0380762Y1018910
X0382611Y1022114
X0377062Y1018910
X0375211Y1022114
X0382611Y1028523
X0380762Y1031727
X0375211Y1028523
X0377062Y1031727
X0395562Y0999684
X0393711Y1002888
X0388162Y0999684
X0390011Y1002888
X0384029Y0915466
X0376629Y0915466
X0380329Y0915466
X0372929Y0915466
X0380329Y0909057
X0382178Y0912262
X0376629Y0909057
X0374778Y0912262
X0382178Y0918670
X0380329Y0921875
X0374778Y0918670
X0376629Y0921875
X0376629Y0966735
X0380329Y0966735
X0382178Y0969939
X0374778Y0969939
X0384029Y0896240
X0384029Y0934691
X0384029Y0953917
X0376629Y0896240
X0376629Y0934691
X0376629Y0953917
X0380329Y0896240
X0380329Y0934691
X0380329Y0953917
X0372929Y0896240
X0372929Y0934691
X0372929Y0953917
X0374778Y0937896
X0376629Y0941100
X0380329Y0947509
X0382178Y0950713
X0376629Y0947509
X0374778Y0950713
X0382178Y0957122
X0385878Y0893036
X0374778Y0893036
X0380329Y0960326
X0382178Y0893036
X0382178Y0899445
X0380329Y0902649
X0374778Y0899445
X0376629Y0902649
X0374778Y0957122
X0380329Y0928283
X0382178Y0931488
X0376629Y0928283
X0374778Y0931488
X0382178Y0937896
X0380329Y0941100
X0376629Y0960326
X0402529Y0973143
X0402529Y0979552
X0400678Y0976347
X0398829Y0973143
X0382178Y0848176
X0378479Y0841467
X0374778Y0848176
X0372927Y0844971
X0437678Y0848176
X0430278Y0848176
X0426578Y0848176
X0422879Y0841467
X0419178Y0848176
X0415479Y0841467
X0411778Y0848176
X0408079Y0841467
X0404378Y0848176
X0402527Y0844971
X0396978Y0848176
X0393279Y0841467
X0389578Y0848176
X0385879Y0841467
X0384027Y0844971
X0380327Y0844971
X0376627Y0844971
X0435829Y0844671
X0433978Y0848176
X0428427Y0844971
X0424727Y0844971
X0421027Y0844971
X0417327Y0844971
X0413627Y0844971
X0409927Y0844971
X0406227Y0844971
X0400679Y0841467
X0398827Y0844971
X0395127Y0844971
X0391427Y0844971
X0387727Y0844971
X0443227Y0844671
X0448778Y0848176
X0452479Y0841467
X0456178Y0848176
X0461727Y0844971
X0465427Y0844971
X0469127Y0844971
X0446927Y0844671
X0450628Y0844971
X0454327Y0844971
X0458027Y0844971
X0459879Y0841467
X0463578Y0848176
X0467279Y0841467
X0470978Y0848176
X0498727Y0844971
X0502427Y0844971
X0506127Y0844971
X0507978Y0848176
X0513527Y0844971
X0515378Y0848176
X0520927Y0844971
X0522778Y0848176
X0530178Y0848176
X0472827Y0844971
X0474679Y0841467
X0478378Y0848176
X0482079Y0841467
X0485778Y0848176
X0491327Y0844971
X0495027Y0844971
X0533878Y0848176
X0496878Y0841467
X0500578Y0848176
X0504279Y0841467
X0509827Y0844971
X0511679Y0841467
X0517227Y0844971
X0519079Y0841467
X0524627Y0844971
X0526478Y0848176
X0476527Y0844971
X0480227Y0844971
X0483927Y0844971
X0487627Y0844971
X0489478Y0841467
X0493178Y0848176
X0532028Y0844671
X0541279Y0854584
X0541279Y0860993
X0539429Y0857789
X0543130Y0857789
X0539429Y0851380
X0543129Y0851380
X0533879Y0854584
X0535729Y0857789
X0546828Y0864197
X0543128Y0864197
X0532029Y0864197
X0535729Y0864197
X0504278Y0905853
X0496878Y0905853
X0507978Y0905853
X0500578Y0905853
X0504278Y0899445
X0506129Y0902649
X0500578Y0899445
X0498729Y0902649
X0506129Y0909057
X0504278Y0912262
X0498729Y0909057
X0500578Y0912262
X0506129Y0960326
X0498729Y0960326
X0504278Y0957122
X0500578Y0957122
X0507978Y0925079
X0504278Y0944304
X0500578Y0925079
X0500578Y0944304
X0504278Y0925079
X0507978Y0944304
X0496878Y0925079
X0496878Y0944304
X0498729Y0928283
X0504278Y0931488
X0504278Y0937896
X0506129Y0941100
X0500578Y0937896
X0498729Y0941100
X0506129Y0947509
X0504278Y0950713
X0498729Y0947509
X0504278Y0918670
X0506129Y0921875
X0500578Y0918670
X0498729Y0921875
X0506129Y0928283
X0500578Y0931488
X0500578Y0950713
X0493178Y0976347
X0491329Y0979552
X0485778Y0976347
X0487629Y0979552
X0525062Y0999684
X0526911Y1002888
X0532461Y0999684
X0530611Y1002888
X0513962Y0999684
X0512111Y1002888
X0517661Y0999684
X0519513Y1002888
X0504711Y1034931
X0504711Y1054157
X0504711Y1073383
X0497311Y1034931
X0497311Y1054157
X0501011Y1073383
X0508411Y1034931
X0508411Y1054157
X0508411Y1073383
X0501011Y1034931
X0501011Y1054157
X0497311Y1073383
X0499162Y1076587
X0501011Y1079791
X0504711Y1047749
X0506562Y1050952
X0501011Y1047749
X0499162Y1050952
X0506562Y1057361
X0504711Y1060565
X0499162Y1057361
X0501011Y1060565
X0504711Y1066974
X0506562Y1070178
X0501011Y1066974
X0499162Y1070178
X0506562Y1076587
X0504711Y1079791
X0504711Y1028523
X0506562Y1031727
X0501011Y1028523
X0499162Y1031727
X0506562Y1038136
X0504711Y1041340
X0499162Y1038136
X0501011Y1041340
X0499162Y0999684
X0501011Y1002888
X0506561Y0999684
X0504711Y1002888
X0504711Y1092608
X0501011Y1092608
X0508411Y1092608
X0497311Y1092608
X0504711Y1086200
X0506562Y1089404
X0501011Y1086200
X0499162Y1089404
X0506561Y1095813
X0515811Y1099017
X0510262Y1095813
X0517662Y1102221
X0620799Y0957546
X0650499Y0957546
X0620799Y0960892
X0650499Y0960892
X0755841Y0783530
X0755841Y0770144
X0755841Y0776837
X0739699Y0773491
X0739699Y0780184
X0755841Y0857152
X0739699Y0790223
X0739699Y0863845
X0755841Y0786877
X0755841Y0860499
X0739699Y0786877
X0739699Y0860499
X0739699Y0870538
X0739699Y0877231
X0755841Y0880577
X0755841Y0793570
X0755841Y0800263
X0739699Y0796916
X0739699Y0803609
X0755841Y0843766
X0755841Y0850459
X0739699Y0847113
X0739699Y0853806
X0755841Y0867192
X0755841Y0873885
X0739699Y0957546
X0769399Y0957546
X0755841Y0893963
X0739699Y0900656
X0755841Y0897310
X0739699Y0897310
X0755841Y0887270
X0739699Y0883924
X0739699Y0890617
X0755841Y0904003
X0755841Y0910696
X0739699Y0907349
X0739699Y0914042
X0739699Y0960892
X0769399Y0960892
X0680299Y0957546
X0709899Y0957546
X0680299Y0960892
X0709899Y0960892
X0755841Y1078018
X0755841Y1081365
X0739699Y1081365
X0755741Y1064633
X0755676Y1071326
X0739699Y1067979
X0739699Y1074672
X0755841Y1114829
X0739699Y1084711
X0739699Y1121522
X0755841Y1118176
X0739699Y1118176
X0755841Y1101444
X0755676Y1108137
X0739699Y1104790
X0739699Y1111483
X0755841Y1124869
X0755841Y1131562
X0739699Y1128215
X0739699Y1134908
X0755841Y1175066
X0755676Y1181759
X0739699Y1178412
X0755841Y1088058
X0755841Y1094751
X0739699Y1091404
X0739699Y1098097
X0755676Y1188452
X0739699Y1195144
X0755841Y1191798
X0739699Y1191798
X0739699Y1201837
X0739699Y1208530
X0739699Y1185105
X0755841Y1198491
X0755841Y1205184
X0815241Y1225263
X0799099Y1231955
X0815241Y1228609
X0799099Y1228609
X0815241Y1211877
X0815241Y1218570
X0799099Y1215223
X0799099Y1221916
X0815241Y1235302
X0815241Y1241995
X0799099Y1238648
X0799099Y1245341
X0799099Y0957546
X0828799Y0957546
X0815241Y0964239
X0799099Y0967585
X0844941Y0964239
X0828799Y0967585
X0799099Y0960892
X0828799Y0960892
X0815241Y0820341
X0799099Y0827034
X0815241Y0823688
X0799099Y0823688
X0815241Y0806955
X0815241Y0813648
X0799099Y0810302
X0799099Y0816995
X0815241Y0830381
X0815241Y0837074
X0799099Y0833727
X0799099Y0840420
X1058383Y1225263
X1042241Y1231955
X1058383Y1228609
X1042241Y1228609
X1058383Y1211877
X1058383Y1218570
X1042241Y1215223
X1042241Y1221916
X1058383Y1235302
X1058383Y1241995
X1042241Y1238648
X1042241Y1245341
X1042241Y0957546
X1012541Y0957546
X1058383Y0964239
X1042241Y0967585
X1028683Y0964239
X1012541Y0967585
X1042241Y0960892
X1012541Y0960892
X1058383Y0820341
X1042241Y0827034
X1058383Y0823688
X1042241Y0823688
X1058383Y0806955
X1058383Y0813648
X1042241Y0810302
X1042241Y0816995
X1058383Y0830381
X1058383Y0837074
X1042241Y0833727
X1042241Y0840420
X1117783Y0783530
X1117783Y0770144
X1117783Y0776837
X1101641Y0773491
X1101641Y0780184
X1117783Y0857152
X1101641Y0790223
X1101641Y0863845
X1117783Y0786877
X1117783Y0860499
X1101641Y0786877
X1101641Y0860499
X1101641Y0870538
X1101641Y0877231
X1117783Y0880577
X1117783Y0793570
X1117783Y0800263
X1101641Y0796916
X1101641Y0803609
X1117783Y0843766
X1117783Y0850459
X1101641Y0847113
X1101641Y0853806
X1117783Y0867192
X1117783Y0873885
X1101641Y0957546
X1071941Y0957546
X1117783Y0893963
X1101641Y0900656
X1117783Y0897310
X1101641Y0897310
X1117783Y0887270
X1101641Y0883924
X1101641Y0890617
X1117783Y0904003
X1117783Y0910696
X1101641Y0907349
X1101641Y0914042
X1101641Y0960892
X1071941Y0960892
X1161041Y0957546
X1131341Y0957546
X1161041Y0960892
X1131341Y0960892
X1117783Y1078018
X1117783Y1081365
X1101641Y1081365
X1117783Y1064633
X1117783Y1071326
X1101641Y1067979
X1101641Y1074672
X1117783Y1114829
X1101641Y1084711
X1101641Y1121522
X1117783Y1118176
X1101641Y1118176
X1117783Y1101444
X1117783Y1108137
X1101641Y1104790
X1101641Y1111483
X1117783Y1124869
X1117783Y1131562
X1101641Y1128215
X1101641Y1134908
X1117783Y1175066
X1117783Y1181759
X1101641Y1178412
X1117783Y1088058
X1117783Y1094751
X1101641Y1091404
X1101641Y1098097
X1117783Y1188452
X1101641Y1195144
X1117783Y1191798
X1101641Y1191798
X1101641Y1201837
X1101641Y1208530
X1101641Y1185105
X1117783Y1198491
X1117783Y1205184
X1220441Y0957546
X1190741Y0957546
X1220441Y0960892
X1190741Y0960892
X1358320Y0848176
X1354621Y0841467
X1350920Y0848176
X1349069Y0844971
X1343520Y0848176
X1341669Y0844971
X1336120Y0848176
X1334269Y0844971
X1328720Y0848176
X1371269Y0844971
X1365720Y0848176
X1362021Y0841467
X1325020Y0848176
X1360169Y0844971
X1356469Y0844971
X1352769Y0844971
X1347221Y0841467
X1345369Y0844971
X1339821Y0841467
X1337969Y0844971
X1332421Y0841467
X1330569Y0844971
X1369421Y0841467
X1367569Y0844971
X1363869Y0844971
X1326869Y0851380
X1360171Y0915466
X1352771Y0915466
X1356471Y0915466
X1349071Y0915466
X1356471Y0909057
X1358320Y0912262
X1352771Y0909057
X1350920Y0912262
X1358320Y0918670
X1356471Y0921875
X1350920Y0918670
X1352771Y0921875
X1352771Y0966735
X1356471Y0966735
X1358320Y0969939
X1350920Y0969939
X1360171Y0896240
X1360171Y0934691
X1360171Y0953917
X1352771Y0896240
X1352771Y0934691
X1352771Y0953917
X1356471Y0896240
X1356471Y0934691
X1356471Y0953917
X1349071Y0896240
X1349071Y0934691
X1349071Y0953917
X1350920Y0937896
X1352771Y0941100
X1356471Y0947509
X1358320Y0950713
X1352771Y0947509
X1350920Y0950713
X1358320Y0957122
X1362020Y0893036
X1350920Y0893036
X1356471Y0960326
X1358320Y0893036
X1347220Y0893036
X1358320Y0899445
X1356471Y0902649
X1350920Y0899445
X1352771Y0902649
X1350920Y0957122
X1356471Y0928283
X1358320Y0931488
X1352771Y0928283
X1350920Y0931488
X1358320Y0937896
X1356471Y0941100
X1352771Y0960326
X1358753Y1009297
X1356904Y1012501
X1351353Y1009297
X1353204Y1012501
X1356904Y1082995
X1353204Y1082995
X1360604Y1082995
X1349504Y1082995
X1356904Y1076587
X1358753Y1079791
X1353204Y1076587
X1351353Y1079791
X1356904Y0999684
X1358753Y1002888
X1353204Y0999684
X1351353Y1002888
X1356902Y1025318
X1360604Y1044544
X1356904Y1063770
X1349502Y1025318
X1353204Y1044544
X1353204Y1063770
X1360604Y1025318
X1356904Y1044544
X1360604Y1063770
X1353204Y1025318
X1349504Y1044544
X1349504Y1063770
X1351353Y1066974
X1353204Y1070178
X1356904Y1038136
X1358753Y1041340
X1353204Y1038136
X1351353Y1041340
X1358753Y1047749
X1356904Y1050952
X1351353Y1047749
X1353204Y1050952
X1356904Y1057361
X1358753Y1060565
X1353204Y1057361
X1351353Y1060565
X1358753Y1066974
X1356904Y1070178
X1356904Y1018910
X1358753Y1022114
X1353204Y1018910
X1351353Y1022114
X1358753Y1028523
X1356904Y1031727
X1351353Y1028523
X1353204Y1031727
X1371704Y0999684
X1369853Y1002888
X1364304Y0999684
X1366153Y1002888
X1316203Y1121447
X1319903Y1121447
X1318053Y1131060
X1323603Y1127856
X1321753Y1124651
X1338403Y1108630
X1334703Y1115039
X1342103Y1108630
X1345803Y1115039
X1343954Y1111834
X1371704Y1108630
X1368004Y1115039
X1312503Y1121447
X1318054Y1118243
X1316203Y1127856
X1319903Y1127856
X1323603Y1121447
X1334703Y1108630
X1336554Y1111834
X1340254Y1105426
X1342103Y1115039
X1345803Y1108630
X1368004Y1108630
X1369853Y1111834
X1358753Y1086200
X1356904Y1089404
X1351353Y1086200
X1353204Y1089404
X1375404Y1108630
X1379104Y1115039
X1377253Y1111834
X1386504Y1108630
X1384653Y1111834
X1390204Y1115039
X1388353Y1105426
X1395753Y1111834
X1392053Y1105426
X1384653Y1099017
X1379104Y1102221
X1373553Y1105426
X1375404Y1115039
X1379104Y1108630
X1384653Y1105426
X1388353Y1111834
X1392053Y1111834
X1390204Y1102221
X1393904Y1108630
X1395753Y1105426
X1380953Y1099017
X1377253Y1099017
X1406853Y1079791
X1405003Y1076587
X1469320Y0976347
X1467471Y0979552
X1461920Y0976347
X1463771Y0979552
X1378671Y0973143
X1378671Y0979552
X1376820Y0976347
X1374971Y0973143
X1443420Y0893036
X1439720Y0899445
X1434171Y0896240
X1432320Y0899445
X1428621Y0893036
X1423071Y0896240
X1421220Y0893036
X1417520Y0899445
X1441571Y0896240
X1437871Y0896240
X1436020Y0893036
X1430471Y0896240
X1426772Y0896240
X1424920Y0899445
X1419371Y0896240
X1421220Y0899445
X1411971Y0896240
X1408271Y0896240
X1406420Y0893036
X1400871Y0896240
X1399020Y0893036
X1395320Y0899445
X1391620Y0893036
X1387920Y0899445
X1413820Y0893036
X1410120Y0899445
X1404571Y0896240
X1402720Y0899445
X1397171Y0896240
X1393471Y0896240
X1389771Y0896240
X1386071Y0896240
X1413820Y0848176
X1410120Y0848176
X1404569Y0844971
X1400869Y0844971
X1395320Y0848176
X1391621Y0841467
X1387920Y0848176
X1384221Y0841467
X1382369Y0844971
X1378669Y0844971
X1374969Y0844971
X1411969Y0844971
X1406420Y0848176
X1402720Y0848176
X1399021Y0841467
X1397169Y0844971
X1393469Y0844971
X1389769Y0844971
X1386069Y0844971
X1380520Y0848176
X1376821Y0841467
X1373120Y0848176
X1517421Y0854584
X1517421Y0860993
X1515571Y0857789
X1519271Y0857789
X1515571Y0851380
X1519271Y0851380
X1510021Y0854584
X1511871Y0857789
X1522970Y0864197
X1519270Y0864197
X1508171Y0864197
X1511871Y0864197
X1480420Y0905853
X1473020Y0905853
X1484120Y0905853
X1476720Y0905853
X1480420Y0899445
X1482271Y0902649
X1476720Y0899445
X1474871Y0902649
X1482271Y0909057
X1480420Y0912262
X1474871Y0909057
X1476720Y0912262
X1482271Y0960326
X1474871Y0960326
X1480420Y0957122
X1476720Y0957122
X1484120Y0925079
X1480420Y0944304
X1476720Y0925079
X1476720Y0944304
X1480420Y0925079
X1484120Y0944304
X1473020Y0925079
X1473020Y0944304
X1474871Y0928283
X1480420Y0931488
X1480420Y0937896
X1482271Y0941100
X1476720Y0937896
X1474871Y0941100
X1482271Y0947509
X1480420Y0950713
X1474871Y0947509
X1480420Y0918670
X1482271Y0921875
X1476720Y0918670
X1474871Y0921875
X1482271Y0928283
X1476720Y0931488
X1476720Y0950713
X1501204Y0999684
X1503053Y1002888
X1508603Y0999684
X1506753Y1002888
X1490104Y0999684
X1488253Y1002888
X1493803Y0999684
X1495655Y1002888
X1480853Y1034931
X1480853Y1054157
X1480853Y1073383
X1473453Y1034931
X1473453Y1054157
X1477153Y1073383
X1484553Y1034931
X1484553Y1054157
X1484553Y1073383
X1477153Y1034931
X1477153Y1054157
X1473453Y1073383
X1475304Y1076587
X1477153Y1079791
X1480853Y1047749
X1482704Y1050952
X1477153Y1047749
X1475304Y1050952
X1482704Y1057361
X1480853Y1060565
X1475304Y1057361
X1477153Y1060565
X1480853Y1066974
X1482704Y1070178
X1477153Y1066974
X1475304Y1070178
X1482704Y1076587
X1480853Y1079791
X1480853Y1028523
X1482704Y1031727
X1477153Y1028523
X1475304Y1031727
X1482704Y1038136
X1480853Y1041340
X1475304Y1038136
X1477153Y1041340
X1475304Y0999684
X1477153Y1002888
X1482703Y0999684
X1480853Y1002888
X1480853Y1092608
X1477153Y1092608
X1484553Y1092608
X1473453Y1092608
X1480853Y1086200
X1482704Y1089404
X1477153Y1086200
X1475304Y1089404
X1482703Y1095813
X1491953Y1099017
X1486404Y1095813
X1493804Y1102221
X1656441Y0957546
X1656441Y0960892
X1596941Y0957546
X1626641Y0957546
X1596941Y0960892
X1626641Y0960892
X1731983Y0783530
X1731983Y0770144
X1731983Y0776837
X1715841Y0773491
X1715841Y0780184
X1731983Y0857152
X1715841Y0790223
X1715841Y0863845
X1731983Y0786877
X1731983Y0860499
X1715841Y0786877
X1715841Y0860499
X1715841Y0870538
X1715841Y0877231
X1731983Y0880577
X1731983Y0793570
X1731983Y0800263
X1715841Y0796916
X1715841Y0803609
X1731983Y0843766
X1731983Y0850459
X1715841Y0847113
X1715841Y0853806
X1731983Y0867192
X1731983Y0873885
X1715841Y0957546
X1745541Y0957546
X1731983Y0893963
X1715841Y0900656
X1731983Y0897310
X1715841Y0897310
X1731983Y0887270
X1715841Y0883924
X1715841Y0890617
X1731983Y0904003
X1731983Y0910696
X1715841Y0907349
X1715841Y0914042
X1715841Y0960892
X1745541Y0960892
X1686041Y0957546
X1686041Y0960892
X1731983Y1078018
X1731983Y1081365
X1715841Y1081365
X1731883Y1064633
X1731818Y1071326
X1715841Y1067979
X1715841Y1074672
X1731983Y1114829
X1715841Y1084711
X1715841Y1121522
X1731983Y1118176
X1715841Y1118176
X1731983Y1101444
X1731818Y1108137
X1715841Y1104790
X1715841Y1111483
X1731983Y1124869
X1731983Y1131562
X1715841Y1128215
X1715841Y1134908
X1731983Y1175066
X1731818Y1181759
X1715841Y1178412
X1731983Y1088058
X1731983Y1094751
X1715841Y1091404
X1715841Y1098097
X1731818Y1188452
X1715841Y1195144
X1731983Y1191798
X1715841Y1191798
X1715841Y1201837
X1715841Y1208530
X1715841Y1185105
X1731983Y1198491
X1731983Y1205184
X1791383Y1225263
X1775241Y1231955
X1791383Y1228609
X1775241Y1228609
X1791383Y1211877
X1791383Y1218570
X1775241Y1215223
X1775241Y1221916
X1791383Y1235302
X1791383Y1241995
X1775241Y1238648
X1775241Y1245341
X1775241Y0957546
X1804941Y0957546
X1791383Y0964239
X1775241Y0967585
X1821083Y0964239
X1804941Y0967585
X1775241Y0960892
X1804941Y0960892
X1791383Y0820341
X1775241Y0827034
X1791383Y0823688
X1775241Y0823688
X1791383Y0806955
X1791383Y0813648
X1775241Y0810302
X1775241Y0816995
X1791383Y0830381
X1791383Y0837074
X1775241Y0833727
X1775241Y0840420
M00
X0062813Y0415750
X0062812Y0412708
X0269957Y1614292
X0257897Y1614292
X0245837Y1614292
X0233777Y1614292
X0221717Y1614292
X0206257Y1614292
X0197597Y1614292
X0266557Y1614292
X0254497Y1614292
X0242437Y1614292
X0230377Y1614292
X0218317Y1614292
X0209657Y1614292
X0194197Y1614292
X0306137Y1614292
X0294077Y1614292
X0282017Y1614292
X0366437Y1614292
X0354377Y1614292
X0342317Y1614292
X0326857Y1614292
X0318197Y1614292
X0302737Y1614292
X0290677Y1614292
X0278617Y1614292
X0363037Y1614292
X0350977Y1614292
X0338917Y1614292
X0330257Y1614292
X0314797Y1614292
X0378497Y1614292
X0375097Y1614292
X0558575Y0071436
X0555175Y0071436
X0554111Y1614292
X0566171Y1614292
X0481751Y1614292
X0493811Y1614292
X0505871Y1614292
X0517931Y1614292
X0529991Y1614292
X0542051Y1614292
X0550711Y1614292
X0562771Y1614292
X0478351Y1614292
X0490411Y1614292
X0502471Y1614292
X0514531Y1614292
X0526591Y1614292
X0538651Y1614292
X0578231Y1614292
X0590291Y1614292
X0602351Y1614292
X0614411Y1614292
X0626471Y1614292
X0638531Y1614292
X0650591Y1614292
X0659251Y1614292
X0574831Y1614292
X0586891Y1614292
X0598951Y1614292
X0611011Y1614292
X0623071Y1614292
X0635131Y1614292
X0647191Y1614292
X0662651Y1614292
X0626640Y0188752
X0613970Y0188752
X0630040Y0188752
X0617370Y0188752
X0659839Y0047264
X0656439Y0047264
X0723041Y-0009800
X0723041Y-0013200
X0840001Y0016800
X0840001Y0020200
X0907470Y0229554
X0902350Y0222468
X0907470Y0215380
X0902350Y0204894
X0907470Y0226154
X0902350Y0219068
X0907470Y0211980
X0902350Y0208294
X0980899Y0016800
X0980899Y0020200
X0980899Y-0009800
X0980899Y-0013200
X1260472Y1590094
X1248412Y1590094
X1236352Y1590094
X1224292Y1590094
X1208832Y1590094
X1200172Y1590094
X1269132Y1590094
X1257072Y1590094
X1245012Y1590094
X1232952Y1590094
X1220892Y1590094
X1212232Y1590094
X1196772Y1590094
X1365124Y0282744
X1344684Y0280259
X1368524Y0282744
X1348084Y0280259
X1355224Y0284644
X1358624Y0284644
X1308712Y1590094
X1296652Y1590094
X1284592Y1590094
X1272532Y1590094
X1369012Y1590094
X1356952Y1590094
X1344892Y1590094
X1329432Y1590094
X1320772Y1590094
X1305312Y1590094
X1293252Y1590094
X1281192Y1590094
X1365612Y1590094
X1353552Y1590094
X1341492Y1590094
X1332832Y1590094
X1317372Y1590094
X1381072Y1590094
X1377672Y1590094
X1470995Y1614292
X1467595Y1614292
X1460814Y0702892
X1457176Y0692992
X1388976Y0737198
X1378306Y0717608
X1389561Y0720608
X1378306Y0705608
X1389568Y0706108
X1378306Y0693608
X1389568Y0691608
X1460814Y0714892
X1457176Y0704992
X1460814Y0690892
X1385338Y0735098
X1374668Y0719708
X1393199Y0722708
X1374668Y0707708
X1393206Y0708208
X1374668Y0695708
X1393206Y0693708
X1374668Y0683708
X1468876Y0728392
X1457176Y0716992
X1457176Y0680992
X1457176Y0668992
X1378306Y0681608
X1389568Y0677108
X1374668Y0671708
X1389568Y0662608
X1378306Y0657608
X1460814Y0654892
X1460814Y0678892
X1460814Y0666892
X1393206Y0679208
X1378306Y0669608
X1393206Y0664708
X1374668Y0659708
X1457176Y0656992
X1410186Y0197668
X1401406Y0197668
X1392656Y0197668
X1380602Y0197668
X1406786Y0197668
X1398006Y0197668
X1389256Y0197668
X1384002Y0197668
X1432660Y0220018
X1436060Y0220018
X1386630Y0242051
X1380638Y0249094
X1388754Y0257203
X1380522Y0263636
X1386273Y0272070
X1386630Y0238651
X1380638Y0245694
X1388754Y0253803
X1380522Y0260236
X1386273Y0268670
X1475714Y0673992
X1475714Y0659492
X1472076Y0671892
X1472076Y0657392
X1475714Y0717492
X1475714Y0702992
X1475714Y0688492
X1472514Y0730492
X1472076Y0715392
X1472076Y0700892
X1472076Y0686392
X1543355Y1614292
X1555415Y1614292
X1567475Y1614292
X1483055Y1614292
X1495115Y1614292
X1507175Y1614292
X1519235Y1614292
X1531295Y1614292
X1539955Y1614292
X1552015Y1614292
X1564075Y1614292
X1479655Y1614292
X1491715Y1614292
X1503775Y1614292
X1515835Y1614292
X1527895Y1614292
X1579535Y1614292
X1591595Y1614292
X1603655Y1614292
X1615715Y1614292
X1627775Y1614292
X1639835Y1614292
X1648495Y1614292
X1576135Y1614292
X1588195Y1614292
X1600255Y1614292
X1612315Y1614292
X1624375Y1614292
X1636435Y1614292
X1651895Y1614292
M30
